FILE_TYPE = CONNECTIVITY;
{Allegro Design Entry HDL 17.4-2019 S026 (4007227) 1/17/2022}
"PAGE_NUMBER" = 405;
0"NC";
1"P5E_CPU0_P1_RX_DP<15:8>";
2"P5E_CPU0_P1_RX_DP<7:0>";
3"P5E_CPU0_P1_RX_DN<7:0>";
4"P5E_CPU0_P1_RX_DN<15:8>";
5"P5E_CPU0_P1_RX_DP<15>";
6"P5E_CPU0_P1_RX_DN<15>";
7"P5E_CPU0_P1_RX_DP<14>";
8"P5E_CPU0_P1_RX_DN<14>";
9"P5E_CPU0_P1_RX_DN<12>";
10"P5E_CPU0_P1_RX_DN<2>";
11"P5E_CPU0_P1_RX_DN<3>";
12"P5E_CPU0_P1_RX_DN<1>";
13"P5E_CPU0_P1_RX_DN<0>";
14"P5E_CPU0_P1_RX_DN<5>";
15"P5E_CPU0_P1_RX_DN<6>";
16"P5E_CPU0_P1_RX_DN<7>";
17"P5E_CPU0_P1_RX_DN<13>";
18"P5E_CPU0_P1_RX_DN<9>";
19"P5E_CPU0_P1_RX_DN<10>";
20"P5E_CPU0_P1_RX_DN<8>";
21"P5E_CPU0_P1_RX_DN<11>";
22"P5E_CPU0_P1_RX_DN<4>";
23"P5E_CPU0_P1_RX_DP<3>";
24"P5E_CPU0_P1_RX_DP<1>";
25"P5E_CPU0_P1_RX_DP<5>";
26"P5E_CPU0_P1_RX_DP<4>";
27"P5E_CPU0_P1_RX_DP<2>";
28"P5E_CPU0_P1_RX_DP<0>";
29"P5E_CPU0_P1_RX_DP<7>";
30"P5E_CPU0_P1_RX_DP<6>";
31"P5E_CPU0_P1_RX_DP<9>";
32"P5E_CPU0_P1_RX_DP<10>";
33"P5E_CPU0_P1_RX_DP<11>";
34"P5E_CPU0_P1_RX_DP<12>";
35"P5E_CPU0_P1_RX_DP<13>";
36"P5E_CPU0_P1_RX_DP<8>";
%"PT5161LRS"
"6","(-7750,4425)","0","pure_quanta","I1";
;
LOCATION"U6011"
$SEC"6"
CDS_SEC"6"
MATERIAL"IC"
VALUE"PT5161LRS"
PART_TYPE"SMLF"
NEEDS_NO_SIZE"TRUE"
CDS_LMAN_SYM_OUTLINE"-350,1450,300,-1400"
CDS_LIB"pure_quanta"
PART_NUMBER"AJ051610U03";
"A_PETN7"
$PN"CC29"20;
"A_PETP7"
$PN"CA26"36;
"A_PETN6"
$PN"BT29"18;
"A_PETP6"
$PN"BP26"31;
"A_PETN5"
$PN"BJ29"19;
"A_PETP5"
$PN"BG26"32;
"A_PETN4"
$PN"BB29"21;
"A_PETP4"
$PN"AY26"33;
"A_PETN3"
$PN"AR29"9;
"A_PETP3"
$PN"AN26"34;
"A_PETN2"
$PN"AH29"17;
"A_PETP2"
$PN"AF26"35;
"A_PETN1"
$PN"AA29"8;
"A_PETP1"
$PN"W26"7;
"A_PETN0"
$PN"P29"6;
"A_PETP0"
$PN"M26"5;
%"TAP"
"1","(-6725,4625)","0","standard","I10";
;
CDS_LIB"standard"
BODY_TYPE"PLUMBING"
HDL_TAP"TRUE";
"B \NAC \NWC"1;
"S \NAC"
BN"12"34;
%"TAP"
"1","(-6525,4525)","0","standard","I11";
;
CDS_LIB"standard"
BODY_TYPE"PLUMBING"
HDL_TAP"TRUE";
"B \NAC \NWC"4;
"S \NAC"
BN"12"9;
%"TAP"
"1","(-6725,4975)","0","standard","I12";
;
CDS_LIB"standard"
BODY_TYPE"PLUMBING"
HDL_TAP"TRUE";
"B \NAC \NWC"1;
"S \NAC"
BN"13"35;
%"TAP"
"1","(-6725,5325)","0","standard","I13";
;
CDS_LIB"standard"
BODY_TYPE"PLUMBING"
HDL_TAP"TRUE";
"B \NAC \NWC"1;
"S \NAC"
BN"14"7;
%"TAP"
"1","(-6525,4875)","0","standard","I14";
;
CDS_LIB"standard"
BODY_TYPE"PLUMBING"
HDL_TAP"TRUE";
"B \NAC \NWC"4;
"S \NAC"
BN"13"17;
%"TAP"
"1","(-6525,5225)","0","standard","I15";
;
CDS_LIB"standard"
BODY_TYPE"PLUMBING"
HDL_TAP"TRUE";
"B \NAC \NWC"4;
"S \NAC"
BN"14"8;
%"TAP"
"1","(-6725,5675)","0","standard","I16";
;
CDS_LIB"standard"
BODY_TYPE"PLUMBING"
HDL_TAP"TRUE";
"B \NAC \NWC"1;
"S \NAC"
BN"15"5;
%"TAP"
"1","(-6525,5575)","0","standard","I17";
;
CDS_LIB"standard"
BODY_TYPE"PLUMBING"
HDL_TAP"TRUE";
"B \NAC \NWC"4;
"S \NAC"
BN"15"6;
%"TAP"
"1","(-6725,3225)","0","standard","I2";
;
CDS_LIB"standard"
BODY_TYPE"PLUMBING"
HDL_TAP"TRUE";
"B \NAC \NWC"1;
"S \NAC"
BN"8"36;
%"TAP"
"1","(-2175,3225)","0","standard","I20";
;
CDS_LIB"standard"
BODY_TYPE"PLUMBING"
HDL_TAP"TRUE";
"B \NAC \NWC"2;
"S \NAC"
BN"0"28;
%"TAP"
"1","(-1975,3125)","0","standard","I21";
;
CDS_LIB"standard"
BODY_TYPE"PLUMBING"
HDL_TAP"TRUE";
"B \NAC \NWC"3;
"S \NAC"
BN"0"13;
%"TAP"
"1","(-1975,3475)","0","standard","I22";
;
CDS_LIB"standard"
BODY_TYPE"PLUMBING"
HDL_TAP"TRUE";
"B \NAC \NWC"3;
"S \NAC"
BN"1"12;
%"TAP"
"1","(-2175,3575)","0","standard","I23";
;
CDS_LIB"standard"
BODY_TYPE"PLUMBING"
HDL_TAP"TRUE";
"B \NAC \NWC"2;
"S \NAC"
BN"1"24;
%"TAP"
"1","(-2175,3925)","0","standard","I24";
;
CDS_LIB"standard"
BODY_TYPE"PLUMBING"
HDL_TAP"TRUE";
"B \NAC \NWC"2;
"S \NAC"
BN"2"27;
%"TAP"
"1","(-1975,3825)","0","standard","I25";
;
CDS_LIB"standard"
BODY_TYPE"PLUMBING"
HDL_TAP"TRUE";
"B \NAC \NWC"3;
"S \NAC"
BN"2"10;
%"TAP"
"1","(-1975,4175)","0","standard","I26";
;
CDS_LIB"standard"
BODY_TYPE"PLUMBING"
HDL_TAP"TRUE";
"B \NAC \NWC"3;
"S \NAC"
BN"3"11;
%"TAP"
"1","(-1975,4525)","0","standard","I27";
;
CDS_LIB"standard"
BODY_TYPE"PLUMBING"
HDL_TAP"TRUE";
"B \NAC \NWC"3;
"S \NAC"
BN"4"22;
%"TAP"
"1","(-2175,4275)","0","standard","I28";
;
CDS_LIB"standard"
BODY_TYPE"PLUMBING"
HDL_TAP"TRUE";
"B \NAC \NWC"2;
"S \NAC"
BN"3"23;
%"TAP"
"1","(-2175,4625)","0","standard","I29";
;
CDS_LIB"standard"
BODY_TYPE"PLUMBING"
HDL_TAP"TRUE";
"B \NAC \NWC"2;
"S \NAC"
BN"4"26;
%"TAP"
"1","(-6525,3125)","0","standard","I3";
;
CDS_LIB"standard"
BODY_TYPE"PLUMBING"
HDL_TAP"TRUE";
"B \NAC \NWC"4;
"S \NAC"
BN"8"20;
%"TAP"
"1","(-2175,4975)","0","standard","I30";
;
CDS_LIB"standard"
BODY_TYPE"PLUMBING"
HDL_TAP"TRUE";
"B \NAC \NWC"2;
"S \NAC"
BN"5"25;
%"TAP"
"1","(-1975,4875)","0","standard","I31";
;
CDS_LIB"standard"
BODY_TYPE"PLUMBING"
HDL_TAP"TRUE";
"B \NAC \NWC"3;
"S \NAC"
BN"5"14;
%"TAP"
"1","(-1975,5225)","0","standard","I32";
;
CDS_LIB"standard"
BODY_TYPE"PLUMBING"
HDL_TAP"TRUE";
"B \NAC \NWC"3;
"S \NAC"
BN"6"15;
%"TAP"
"1","(-2175,5325)","0","standard","I33";
;
CDS_LIB"standard"
BODY_TYPE"PLUMBING"
HDL_TAP"TRUE";
"B \NAC \NWC"2;
"S \NAC"
BN"6"30;
%"TAP"
"1","(-2175,5675)","0","standard","I34";
;
CDS_LIB"standard"
BODY_TYPE"PLUMBING"
HDL_TAP"TRUE";
"B \NAC \NWC"2;
"S \NAC"
BN"7"29;
%"TAP"
"1","(-1975,5575)","0","standard","I35";
;
CDS_LIB"standard"
BODY_TYPE"PLUMBING"
HDL_TAP"TRUE";
"B \NAC \NWC"3;
"S \NAC"
BN"7"16;
%"PT5161LRS"
"7","(-3200,4425)","0","pure_quanta","I38";
;
LOCATION"U6011"
$SEC"7"
CDS_SEC"7"
MATERIAL"IC"
PART_TYPE"SMLF"
VALUE"PT5161LRS"
CDS_LIB"pure_quanta"
CDS_LMAN_SYM_OUTLINE"-350,1450,300,-1400"
NEEDS_NO_SIZE"TRUE"
PART_NUMBER"AJ051610U03";
"A_PETN15"
$PN"EW29"13;
"A_PETP15"
$PN"EU26"28;
"A_PETN14"
$PN"EM29"12;
"A_PETP14"
$PN"EK26"24;
"A_PETN13"
$PN"EE29"10;
"A_PETP13"
$PN"EC26"27;
"A_PETN12"
$PN"DV29"11;
"A_PETP12"
$PN"DT26"23;
"A_PETN11"
$PN"DL29"22;
"A_PETP11"
$PN"DJ26"26;
"A_PETN10"
$PN"DD29"14;
"A_PETP10"
$PN"DB26"25;
"A_PETN9"
$PN"CU29"15;
"A_PETP9"
$PN"CR26"30;
"A_PETN8"
$PN"CK29"16;
"A_PETP8"
$PN"CH26"29;
%"TAP"
"1","(-6725,3575)","0","standard","I4";
;
CDS_LIB"standard"
BODY_TYPE"PLUMBING"
HDL_TAP"TRUE";
"B \NAC \NWC"1;
"S \NAC"
BN"9"31;
%"TAP"
"1","(-6525,3475)","0","standard","I5";
;
CDS_LIB"standard"
BODY_TYPE"PLUMBING"
HDL_TAP"TRUE";
"B \NAC \NWC"4;
"S \NAC"
BN"9"18;
%"TAP"
"1","(-6525,3825)","0","standard","I6";
;
CDS_LIB"standard"
BODY_TYPE"PLUMBING"
HDL_TAP"TRUE";
"B \NAC \NWC"4;
"S \NAC"
BN"10"19;
%"TAP"
"1","(-6725,3925)","0","standard","I7";
;
CDS_LIB"standard"
BODY_TYPE"PLUMBING"
HDL_TAP"TRUE";
"B \NAC \NWC"1;
"S \NAC"
BN"10"32;
%"TAP"
"1","(-6725,4275)","0","standard","I8";
;
CDS_LIB"standard"
BODY_TYPE"PLUMBING"
HDL_TAP"TRUE";
"B \NAC \NWC"1;
"S \NAC"
BN"11"33;
%"TAP"
"1","(-6525,4175)","0","standard","I9";
;
CDS_LIB"standard"
BODY_TYPE"PLUMBING"
HDL_TAP"TRUE";
"B \NAC \NWC"4;
"S \NAC"
BN"11"21;
END.
